(kicad_pcb
	(version 20260206)
	(generator "pcbnew")
	(generator_version "10.0")
	(general
		(thickness 1.6)
		(legacy_teardrops no)
	)
	(paper "A4")
	(title_block
		(title "01162023_DA0F0TEBIF0_F0T_Expander_BD_F_brd_V02_OCP.brd")
		(comment 1 "Grand Teton / footprints 9089-9096 of 9728")
	)
	(layers
		(0 "F.Cu" signal "TOP")
		(4 "In1.Cu" signal "GND")
		(6 "In2.Cu" signal "VCC")
		(8 "In3.Cu" signal "VCC1")
		(10 "In4.Cu" signal "GND1")
		(12 "In5.Cu" signal "IN1")
		(14 "In6.Cu" signal "GND2")
		(16 "In7.Cu" signal "IN2")
		(18 "In8.Cu" signal "GND3")
		(20 "In9.Cu" signal "IN3")
		(22 "In10.Cu" signal "GND4")
		(24 "In11.Cu" signal "IN4")
		(26 "In12.Cu" signal "GND5")
		(28 "In13.Cu" signal "IN5")
		(30 "In14.Cu" signal "GND6")
		(32 "In15.Cu" signal "IN6")
		(34 "In16.Cu" signal "GND7")
		(2 "B.Cu" signal "BOTTOM")
		(9 "F.Adhes" user "F.Adhesive")
		(11 "B.Adhes" user "B.Adhesive")
		(13 "F.Paste" user "Package Geometry/Pastemask Top")
		(15 "B.Paste" user "Package Geometry/Pastemask Bottom")
		(5 "F.SilkS" user "Ref Des/Silkscreen Top")
		(7 "B.SilkS" user "Ref Des/Silkscreen Bottom")
		(1 "F.Mask" user "Board Geometry/Soldermask Top")
		(3 "B.Mask" user "Board Geometry/Soldermask Bottom")
		(17 "Dwgs.User" user "User.Drawings")
		(19 "Cmts.User" user "User.Comments")
		(21 "Eco1.User" user "User.Eco1")
		(23 "Eco2.User" user "User.Eco2")
		(25 "Edge.Cuts" user "Board Geometry/Outline")
		(27 "Margin" user)
		(31 "F.CrtYd" user "Package Geometry/Place Bound Top")
		(29 "B.CrtYd" user "Package Geometry/Place Bound Bottom")
		(35 "F.Fab" user "Ref Des/Assembly Top")
		(33 "B.Fab" user "Ref Des/Assembly Bottom")
	)
	(footprint ""
		(layer "B.Cu")
		(at 298.119038 -202.16114 -90)
		(property "Reference" "R1041"
			(at 0 0 90)
			(layer "B.SilkS")
			(hide yes)
			(effects
				(font
					(size 1.27 1.27)
				)
				(justify mirror)
			)
		)
		(property "Value" ""
			(at 0 0 90)
			(layer "B.Fab")
			(effects
				(font
					(size 1.27 1.27)
				)
				(justify mirror)
			)
		)
		(duplicate_pad_numbers_are_jumpers no)
		(fp_line
			(start -0.7874 0.4064)
			(end 0.7874 0.4064)
			(stroke
				(width 0.1524)
				(type default)
			)
			(layer "B.SilkS")
		)
		(fp_line
			(start 0.7874 0.4064)
			(end 0.7874 -0.4064)
			(stroke
				(width 0.1524)
				(type default)
			)
			(layer "B.SilkS")
		)
		(fp_line
			(start -0.7874 -0.4064)
			(end -0.7874 0.4064)
			(stroke
				(width 0.1524)
				(type default)
			)
			(layer "B.SilkS")
		)
		(fp_line
			(start 0.7874 -0.4064)
			(end -0.7874 -0.4064)
			(stroke
				(width 0.1524)
				(type default)
			)
			(layer "B.SilkS")
		)
		(fp_line
			(start -0.67945 0.3048)
			(end -0.120396 0.3048)
			(stroke
				(width 0.1)
				(type default)
			)
			(layer "B.Fab")
		)
		(fp_line
			(start -0.120396 0.3048)
			(end -0.120396 0.2794)
			(stroke
				(width 0.1)
				(type default)
			)
			(layer "B.Fab")
		)
		(fp_line
			(start 0.12065 0.3048)
			(end 0.67945 0.3048)
			(stroke
				(width 0.1)
				(type default)
			)
			(layer "B.Fab")
		)
		(fp_line
			(start 0.67945 0.3048)
			(end 0.67945 -0.305054)
			(stroke
				(width 0.1)
				(type default)
			)
			(layer "B.Fab")
		)
		(fp_line
			(start -0.120396 0.2794)
			(end 0.12065 0.2794)
			(stroke
				(width 0.1)
				(type default)
			)
			(layer "B.Fab")
		)
		(fp_line
			(start 0.12065 0.2794)
			(end 0.12065 0.3048)
			(stroke
				(width 0.1)
				(type default)
			)
			(layer "B.Fab")
		)
		(fp_line
			(start -0.12065 -0.2794)
			(end -0.12065 -0.3048)
			(stroke
				(width 0.1)
				(type default)
			)
			(layer "B.Fab")
		)
		(fp_line
			(start 0.12065 -0.2794)
			(end -0.12065 -0.2794)
			(stroke
				(width 0.1)
				(type default)
			)
			(layer "B.Fab")
		)
		(fp_line
			(start -0.67945 -0.3048)
			(end -0.67945 0.3048)
			(stroke
				(width 0.1)
				(type default)
			)
			(layer "B.Fab")
		)
		(fp_line
			(start -0.12065 -0.3048)
			(end -0.67945 -0.3048)
			(stroke
				(width 0.1)
				(type default)
			)
			(layer "B.Fab")
		)
		(fp_line
			(start 0.12065 -0.305054)
			(end 0.12065 -0.2794)
			(stroke
				(width 0.1)
				(type default)
			)
			(layer "B.Fab")
		)
		(fp_line
			(start 0.67945 -0.305054)
			(end 0.12065 -0.305054)
			(stroke
				(width 0.1)
				(type default)
			)
			(layer "B.Fab")
		)
		(pad "1" smd circle
			(at 0.40005 0 90)
			(size 0 0)
			(layers "B.Cu" "B.Mask" "B.Paste")
			(net "GND")
		)
		(pad "2" smd circle
			(at -0.40005 0 90)
			(size 0 0)
			(layers "B.Cu" "B.Mask" "B.Paste")
			(net "SPI_BIC1_CS0_LS23_N_DIR1")
		)
	)
	(footprint ""
		(layer "B.Cu")
		(at 163.874958 -296.7482 -90)
		(property "Reference" "C3215"
			(at 0 0 90)
			(layer "B.SilkS")
			(hide yes)
			(effects
				(font
					(size 1.27 1.27)
				)
				(justify mirror)
			)
		)
		(property "Value" ""
			(at 0 0 90)
			(layer "B.Fab")
			(effects
				(font
					(size 1.27 1.27)
				)
				(justify mirror)
			)
		)
		(duplicate_pad_numbers_are_jumpers no)
		(fp_line
			(start -0.299974 0.150114)
			(end 0.299974 0.150114)
			(stroke
				(width 0.1)
				(type default)
			)
			(layer "B.Fab")
		)
		(fp_line
			(start 0.299974 0.150114)
			(end 0.299974 -0.150114)
			(stroke
				(width 0.1)
				(type default)
			)
			(layer "B.Fab")
		)
		(fp_line
			(start -0.299974 -0.150114)
			(end -0.299974 0.150114)
			(stroke
				(width 0.1)
				(type default)
			)
			(layer "B.Fab")
		)
		(fp_line
			(start 0.299974 -0.150114)
			(end -0.299974 -0.150114)
			(stroke
				(width 0.1)
				(type default)
			)
			(layer "B.Fab")
		)
		(pad "1" smd rect
			(at 0.2667 0 90)
			(size 0.3048 0.381)
			(layers "B.Cu" "B.Mask" "B.Paste")
			(net "PCEPLL3_VDDA18_PEX1")
		)
		(pad "2" smd rect
			(at -0.2667 0 90)
			(size 0.3048 0.381)
			(layers "B.Cu" "B.Mask" "B.Paste")
			(net "GND")
		)
	)
	(footprint ""
		(layer "B.Cu")
		(at 271.899888 -288.774886 -90)
		(property "Reference" "R3472"
			(at 0 0 90)
			(layer "B.SilkS")
			(hide yes)
			(effects
				(font
					(size 1.27 1.27)
				)
				(justify mirror)
			)
		)
		(property "Value" ""
			(at 0 0 90)
			(layer "B.Fab")
			(effects
				(font
					(size 1.27 1.27)
				)
				(justify mirror)
			)
		)
		(duplicate_pad_numbers_are_jumpers no)
		(fp_line
			(start -0.7874 0.4064)
			(end 0.7874 0.4064)
			(stroke
				(width 0.1524)
				(type default)
			)
			(layer "B.SilkS")
		)
		(fp_line
			(start 0.7874 0.4064)
			(end 0.7874 -0.4064)
			(stroke
				(width 0.1524)
				(type default)
			)
			(layer "B.SilkS")
		)
		(fp_line
			(start -0.7874 -0.4064)
			(end -0.7874 0.4064)
			(stroke
				(width 0.1524)
				(type default)
			)
			(layer "B.SilkS")
		)
		(fp_line
			(start 0.7874 -0.4064)
			(end -0.7874 -0.4064)
			(stroke
				(width 0.1524)
				(type default)
			)
			(layer "B.SilkS")
		)
		(fp_line
			(start -0.67945 0.3048)
			(end -0.120396 0.3048)
			(stroke
				(width 0.1)
				(type default)
			)
			(layer "B.Fab")
		)
		(fp_line
			(start -0.120396 0.3048)
			(end -0.120396 0.2794)
			(stroke
				(width 0.1)
				(type default)
			)
			(layer "B.Fab")
		)
		(fp_line
			(start 0.12065 0.3048)
			(end 0.67945 0.3048)
			(stroke
				(width 0.1)
				(type default)
			)
			(layer "B.Fab")
		)
		(fp_line
			(start 0.67945 0.3048)
			(end 0.67945 -0.305054)
			(stroke
				(width 0.1)
				(type default)
			)
			(layer "B.Fab")
		)
		(fp_line
			(start -0.120396 0.2794)
			(end 0.12065 0.2794)
			(stroke
				(width 0.1)
				(type default)
			)
			(layer "B.Fab")
		)
		(fp_line
			(start 0.12065 0.2794)
			(end 0.12065 0.3048)
			(stroke
				(width 0.1)
				(type default)
			)
			(layer "B.Fab")
		)
		(fp_line
			(start -0.12065 -0.2794)
			(end -0.12065 -0.3048)
			(stroke
				(width 0.1)
				(type default)
			)
			(layer "B.Fab")
		)
		(fp_line
			(start 0.12065 -0.2794)
			(end -0.12065 -0.2794)
			(stroke
				(width 0.1)
				(type default)
			)
			(layer "B.Fab")
		)
		(fp_line
			(start -0.67945 -0.3048)
			(end -0.67945 0.3048)
			(stroke
				(width 0.1)
				(type default)
			)
			(layer "B.Fab")
		)
		(fp_line
			(start -0.12065 -0.3048)
			(end -0.67945 -0.3048)
			(stroke
				(width 0.1)
				(type default)
			)
			(layer "B.Fab")
		)
		(fp_line
			(start 0.12065 -0.305054)
			(end 0.12065 -0.2794)
			(stroke
				(width 0.1)
				(type default)
			)
			(layer "B.Fab")
		)
		(fp_line
			(start 0.67945 -0.305054)
			(end 0.12065 -0.305054)
			(stroke
				(width 0.1)
				(type default)
			)
			(layer "B.Fab")
		)
		(pad "1" smd circle
			(at 0.40005 0 90)
			(size 0 0)
			(layers "B.Cu" "B.Mask" "B.Paste")
			(net "SPI_PEX2_SDIO3_R")
		)
		(pad "2" smd circle
			(at -0.40005 0 90)
			(size 0 0)
			(layers "B.Cu" "B.Mask" "B.Paste")
			(net "SPI_PEX2_SDIO3")
		)
	)
	(footprint ""
		(layer "B.Cu")
		(at 299.250608 -225.780346 180)
		(property "Reference" "C2748"
			(at 0 0 0)
			(layer "B.SilkS")
			(hide yes)
			(effects
				(font
					(size 1.27 1.27)
				)
				(justify mirror)
			)
		)
		(property "Value" ""
			(at 0 0 0)
			(layer "B.Fab")
			(effects
				(font
					(size 1.27 1.27)
				)
				(justify mirror)
			)
		)
		(duplicate_pad_numbers_are_jumpers no)
		(fp_line
			(start 0.7874 0.4064)
			(end 0.7874 -0.4064)
			(stroke
				(width 0.1524)
				(type default)
			)
			(layer "B.SilkS")
		)
		(fp_line
			(start 0.7874 -0.4064)
			(end -0.7874 -0.4064)
			(stroke
				(width 0.1524)
				(type default)
			)
			(layer "B.SilkS")
		)
		(fp_line
			(start -0.7874 0.4064)
			(end 0.7874 0.4064)
			(stroke
				(width 0.1524)
				(type default)
			)
			(layer "B.SilkS")
		)
		(fp_line
			(start -0.7874 -0.4064)
			(end -0.7874 0.4064)
			(stroke
				(width 0.1524)
				(type default)
			)
			(layer "B.SilkS")
		)
		(fp_line
			(start 0.67945 0.3048)
			(end 0.67945 -0.305054)
			(stroke
				(width 0.1)
				(type default)
			)
			(layer "B.Fab")
		)
		(fp_line
			(start 0.67945 -0.305054)
			(end 0.12065 -0.305054)
			(stroke
				(width 0.1)
				(type default)
			)
			(layer "B.Fab")
		)
		(fp_line
			(start 0.12065 0.3048)
			(end 0.67945 0.3048)
			(stroke
				(width 0.1)
				(type default)
			)
			(layer "B.Fab")
		)
		(fp_line
			(start 0.12065 0.2794)
			(end 0.12065 0.3048)
			(stroke
				(width 0.1)
				(type default)
			)
			(layer "B.Fab")
		)
		(fp_line
			(start 0.12065 -0.2794)
			(end -0.12065 -0.2794)
			(stroke
				(width 0.1)
				(type default)
			)
			(layer "B.Fab")
		)
		(fp_line
			(start 0.12065 -0.305054)
			(end 0.12065 -0.2794)
			(stroke
				(width 0.1)
				(type default)
			)
			(layer "B.Fab")
		)
		(fp_line
			(start -0.120396 0.3048)
			(end -0.120396 0.2794)
			(stroke
				(width 0.1)
				(type default)
			)
			(layer "B.Fab")
		)
		(fp_line
			(start -0.120396 0.2794)
			(end 0.12065 0.2794)
			(stroke
				(width 0.1)
				(type default)
			)
			(layer "B.Fab")
		)
		(fp_line
			(start -0.12065 -0.2794)
			(end -0.12065 -0.3048)
			(stroke
				(width 0.1)
				(type default)
			)
			(layer "B.Fab")
		)
		(fp_line
			(start -0.12065 -0.3048)
			(end -0.67945 -0.3048)
			(stroke
				(width 0.1)
				(type default)
			)
			(layer "B.Fab")
		)
		(fp_line
			(start -0.67945 0.3048)
			(end -0.120396 0.3048)
			(stroke
				(width 0.1)
				(type default)
			)
			(layer "B.Fab")
		)
		(fp_line
			(start -0.67945 -0.3048)
			(end -0.67945 0.3048)
			(stroke
				(width 0.1)
				(type default)
			)
			(layer "B.Fab")
		)
		(pad "1" smd circle
			(at 0.40005 0)
			(size 0 0)
			(layers "B.Cu" "B.Mask" "B.Paste")
			(net "GND")
		)
		(pad "2" smd circle
			(at -0.40005 0)
			(size 0 0)
			(layers "B.Cu" "B.Mask" "B.Paste")
			(net "P3V3_AUX")
		)
	)
	(footprint ""
		(layer "B.Cu")
		(at 338.768436 -308.749954 90)
		(property "Reference" "C4307"
			(at 0 0 90)
			(layer "B.SilkS")
			(hide yes)
			(effects
				(font
					(size 1.27 1.27)
				)
				(justify mirror)
			)
		)
		(property "Value" ""
			(at 0 0 90)
			(layer "B.Fab")
			(effects
				(font
					(size 1.27 1.27)
				)
				(justify mirror)
			)
		)
		(duplicate_pad_numbers_are_jumpers no)
		(fp_line
			(start 0.299974 -0.150114)
			(end -0.299974 -0.150114)
			(stroke
				(width 0.1)
				(type default)
			)
			(layer "B.Fab")
		)
		(fp_line
			(start -0.299974 -0.150114)
			(end -0.299974 0.150114)
			(stroke
				(width 0.1)
				(type default)
			)
			(layer "B.Fab")
		)
		(fp_line
			(start 0.299974 0.150114)
			(end 0.299974 -0.150114)
			(stroke
				(width 0.1)
				(type default)
			)
			(layer "B.Fab")
		)
		(fp_line
			(start -0.299974 0.150114)
			(end 0.299974 0.150114)
			(stroke
				(width 0.1)
				(type default)
			)
			(layer "B.Fab")
		)
		(pad "1" smd rect
			(at 0.2667 0 270)
			(size 0.3048 0.381)
			(layers "B.Cu" "B.Mask" "B.Paste")
			(net "P0V8_PEX2")
		)
		(pad "2" smd rect
			(at -0.2667 0 270)
			(size 0.3048 0.381)
			(layers "B.Cu" "B.Mask" "B.Paste")
			(net "GND")
		)
	)
	(footprint ""
		(layer "B.Cu")
		(at 128.530604 -325.61149 -90)
		(property "Reference" "C4255"
			(at 0 0 90)
			(layer "B.SilkS")
			(hide yes)
			(effects
				(font
					(size 1.27 1.27)
				)
				(justify mirror)
			)
		)
		(property "Value" ""
			(at 0 0 90)
			(layer "B.Fab")
			(effects
				(font
					(size 1.27 1.27)
				)
				(justify mirror)
			)
		)
		(duplicate_pad_numbers_are_jumpers no)
		(fp_line
			(start -1.2954 0.5842)
			(end 1.2954 0.5842)
			(stroke
				(width 0.1524)
				(type default)
			)
			(layer "B.SilkS")
		)
		(fp_line
			(start 1.2954 0.5842)
			(end 1.2954 -0.5842)
			(stroke
				(width 0.1524)
				(type default)
			)
			(layer "B.SilkS")
		)
		(fp_line
			(start -1.2954 -0.5842)
			(end -1.2954 0.5842)
			(stroke
				(width 0.1524)
				(type default)
			)
			(layer "B.SilkS")
		)
		(fp_line
			(start 1.2954 -0.5842)
			(end -1.2954 -0.5842)
			(stroke
				(width 0.1524)
				(type default)
			)
			(layer "B.SilkS")
		)
		(fp_line
			(start -0.8636 0.4572)
			(end 0.8636 0.4572)
			(stroke
				(width 0.1)
				(type default)
			)
			(layer "B.Fab")
		)
		(fp_line
			(start 0.8636 0.4572)
			(end 0.8636 0.4064)
			(stroke
				(width 0.1)
				(type default)
			)
			(layer "B.Fab")
		)
		(fp_line
			(start -1.1938 0.4064)
			(end -0.8636 0.4064)
			(stroke
				(width 0.1)
				(type default)
			)
			(layer "B.Fab")
		)
		(fp_line
			(start -0.8636 0.4064)
			(end -0.8636 0.4572)
			(stroke
				(width 0.1)
				(type default)
			)
			(layer "B.Fab")
		)
		(fp_line
			(start 0.8636 0.4064)
			(end 1.1938 0.4064)
			(stroke
				(width 0.1)
				(type default)
			)
			(layer "B.Fab")
		)
		(fp_line
			(start 1.1938 0.4064)
			(end 1.1938 -0.4064)
			(stroke
				(width 0.1)
				(type default)
			)
			(layer "B.Fab")
		)
		(fp_line
			(start -1.1938 -0.4064)
			(end -1.1938 0.4064)
			(stroke
				(width 0.1)
				(type default)
			)
			(layer "B.Fab")
		)
		(fp_line
			(start -0.8636 -0.4064)
			(end -1.1938 -0.4064)
			(stroke
				(width 0.1)
				(type default)
			)
			(layer "B.Fab")
		)
		(fp_line
			(start 0.8636 -0.4064)
			(end 0.8636 -0.4572)
			(stroke
				(width 0.1)
				(type default)
			)
			(layer "B.Fab")
		)
		(fp_line
			(start 1.1938 -0.4064)
			(end 0.8636 -0.4064)
			(stroke
				(width 0.1)
				(type default)
			)
			(layer "B.Fab")
		)
		(fp_line
			(start -0.8636 -0.4572)
			(end -0.8636 -0.4064)
			(stroke
				(width 0.1)
				(type default)
			)
			(layer "B.Fab")
		)
		(fp_line
			(start 0.8636 -0.4572)
			(end -0.8636 -0.4572)
			(stroke
				(width 0.1)
				(type default)
			)
			(layer "B.Fab")
		)
		(pad "1" smd rect
			(at 0.7366 0 180)
			(size 0.7112 0.8128)
			(layers "B.Cu" "B.Mask" "B.Paste")
			(net "P0V8_SERDES_VDDA_PEX1_C1")
		)
		(pad "2" smd rect
			(at -0.7366 0 180)
			(size 0.7112 0.8128)
			(layers "B.Cu" "B.Mask" "B.Paste")
			(net "GND")
		)
	)
	(footprint ""
		(layer "B.Cu")
		(at 403.199854 -290.199826 90)
		(property "Reference" "C1982"
			(at 0 0 90)
			(layer "B.SilkS")
			(hide yes)
			(effects
				(font
					(size 1.27 1.27)
				)
				(justify mirror)
			)
		)
		(property "Value" ""
			(at 0 0 90)
			(layer "B.Fab")
			(effects
				(font
					(size 1.27 1.27)
				)
				(justify mirror)
			)
		)
		(duplicate_pad_numbers_are_jumpers no)
		(fp_line
			(start 0.299974 -0.150114)
			(end -0.299974 -0.150114)
			(stroke
				(width 0.1)
				(type default)
			)
			(layer "B.Fab")
		)
		(fp_line
			(start -0.299974 -0.150114)
			(end -0.299974 0.150114)
			(stroke
				(width 0.1)
				(type default)
			)
			(layer "B.Fab")
		)
		(fp_line
			(start 0.299974 0.150114)
			(end 0.299974 -0.150114)
			(stroke
				(width 0.1)
				(type default)
			)
			(layer "B.Fab")
		)
		(fp_line
			(start -0.299974 0.150114)
			(end 0.299974 0.150114)
			(stroke
				(width 0.1)
				(type default)
			)
			(layer "B.Fab")
		)
		(pad "1" smd rect
			(at 0.2667 0 270)
			(size 0.3048 0.381)
			(layers "B.Cu" "B.Mask" "B.Paste")
			(net "P0V8_SERDES_VDDA_PEX3")
		)
		(pad "2" smd rect
			(at -0.2667 0 270)
			(size 0.3048 0.381)
			(layers "B.Cu" "B.Mask" "B.Paste")
			(net "GND")
		)
	)
	(footprint ""
		(layer "B.Cu")
		(at 129.58826 -308.580028 90)
		(property "Reference" "C4249"
			(at 0 0 90)
			(layer "B.SilkS")
			(hide yes)
			(effects
				(font
					(size 1.27 1.27)
				)
				(justify mirror)
			)
		)
		(property "Value" ""
			(at 0 0 90)
			(layer "B.Fab")
			(effects
				(font
					(size 1.27 1.27)
				)
				(justify mirror)
			)
		)
		(duplicate_pad_numbers_are_jumpers no)
		(fp_line
			(start 1.2954 -0.5842)
			(end -1.2954 -0.5842)
			(stroke
				(width 0.1524)
				(type default)
			)
			(layer "B.SilkS")
		)
		(fp_line
			(start -1.2954 -0.5842)
			(end -1.2954 0.5842)
			(stroke
				(width 0.1524)
				(type default)
			)
			(layer "B.SilkS")
		)
		(fp_line
			(start 1.2954 0.5842)
			(end 1.2954 -0.5842)
			(stroke
				(width 0.1524)
				(type default)
			)
			(layer "B.SilkS")
		)
		(fp_line
			(start -1.2954 0.5842)
			(end 1.2954 0.5842)
			(stroke
				(width 0.1524)
				(type default)
			)
			(layer "B.SilkS")
		)
		(fp_line
			(start 0.8636 -0.4572)
			(end -0.8636 -0.4572)
			(stroke
				(width 0.1)
				(type default)
			)
			(layer "B.Fab")
		)
		(fp_line
			(start -0.8636 -0.4572)
			(end -0.8636 -0.4064)
			(stroke
				(width 0.1)
				(type default)
			)
			(layer "B.Fab")
		)
		(fp_line
			(start 1.1938 -0.4064)
			(end 0.8636 -0.4064)
			(stroke
				(width 0.1)
				(type default)
			)
			(layer "B.Fab")
		)
		(fp_line
			(start 0.8636 -0.4064)
			(end 0.8636 -0.4572)
			(stroke
				(width 0.1)
				(type default)
			)
			(layer "B.Fab")
		)
		(fp_line
			(start -0.8636 -0.4064)
			(end -1.1938 -0.4064)
			(stroke
				(width 0.1)
				(type default)
			)
			(layer "B.Fab")
		)
		(fp_line
			(start -1.1938 -0.4064)
			(end -1.1938 0.4064)
			(stroke
				(width 0.1)
				(type default)
			)
			(layer "B.Fab")
		)
		(fp_line
			(start 1.1938 0.4064)
			(end 1.1938 -0.4064)
			(stroke
				(width 0.1)
				(type default)
			)
			(layer "B.Fab")
		)
		(fp_line
			(start 0.8636 0.4064)
			(end 1.1938 0.4064)
			(stroke
				(width 0.1)
				(type default)
			)
			(layer "B.Fab")
		)
		(fp_line
			(start -0.8636 0.4064)
			(end -0.8636 0.4572)
			(stroke
				(width 0.1)
				(type default)
			)
			(layer "B.Fab")
		)
		(fp_line
			(start -1.1938 0.4064)
			(end -0.8636 0.4064)
			(stroke
				(width 0.1)
				(type default)
			)
			(layer "B.Fab")
		)
		(fp_line
			(start 0.8636 0.4572)
			(end 0.8636 0.4064)
			(stroke
				(width 0.1)
				(type default)
			)
			(layer "B.Fab")
		)
		(fp_line
			(start -0.8636 0.4572)
			(end 0.8636 0.4572)
			(stroke
				(width 0.1)
				(type default)
			)
			(layer "B.Fab")
		)
		(pad "1" smd rect
			(at 0.7366 0)
			(size 0.7112 0.8128)
			(layers "B.Cu" "B.Mask" "B.Paste")
			(net "P0V8_PEX1")
		)
		(pad "2" smd rect
			(at -0.7366 0)
			(size 0.7112 0.8128)
			(layers "B.Cu" "B.Mask" "B.Paste")
			(net "GND")
		)
	)
)
